(kicad_pcb
	(version 20260206)
	(generator "pcbnew")
	(generator_version "10.0")
	(general
		(thickness 1.6)
		(legacy_teardrops no)
	)
	(paper "A4")
	(title_block
		(title "04192023_DAF0TMB3IC0_F0TG_MB_C_brd_V02_OCP.brd")
		(comment 1 "Grand Teton / footprints 2587-2593 of 8354")
	)
	(layers
		(0 "F.Cu" signal "TOP")
		(4 "In1.Cu" signal "GND")
		(6 "In2.Cu" signal "IN1")
		(8 "In3.Cu" signal "GND1")
		(10 "In4.Cu" signal "IN2")
		(12 "In5.Cu" signal "GND2")
		(14 "In6.Cu" signal "IN3")
		(16 "In7.Cu" signal "GND3")
		(18 "In8.Cu" signal "VCC")
		(20 "In9.Cu" signal "VCC1")
		(22 "In10.Cu" signal "GND4")
		(24 "In11.Cu" signal "IN4")
		(26 "In12.Cu" signal "GND5")
		(28 "In13.Cu" signal "IN5")
		(30 "In14.Cu" signal "GND6")
		(32 "In15.Cu" signal "IN6")
		(34 "In16.Cu" signal "GND7")
		(2 "B.Cu" signal "BOTTOM")
		(9 "F.Adhes" user "F.Adhesive")
		(11 "B.Adhes" user "B.Adhesive")
		(13 "F.Paste" user "Package Geometry/Pastemask Top")
		(15 "B.Paste" user "Package Geometry/Pastemask Bottom")
		(5 "F.SilkS" user "Ref Des/Silkscreen Top")
		(7 "B.SilkS" user "Ref Des/Silkscreen Bottom")
		(1 "F.Mask" user "Board Geometry/Soldermask Top")
		(3 "B.Mask" user "Board Geometry/Soldermask Bottom")
		(17 "Dwgs.User" user "User.Drawings")
		(19 "Cmts.User" user "User.Comments")
		(21 "Eco1.User" user "User.Eco1")
		(23 "Eco2.User" user "User.Eco2")
		(25 "Edge.Cuts" user "Board Geometry/Outline")
		(27 "Margin" user)
		(31 "F.CrtYd" user "Package Geometry/Place Bound Top")
		(29 "B.CrtYd" user "Package Geometry/Place Bound Bottom")
		(35 "F.Fab" user "Ref Des/Assembly Top")
		(33 "B.Fab" user "Ref Des/Assembly Bottom")
	)
	(footprint ""
		(layer "F.Cu")
		(at 463.439764 -399.030952)
		(property "Reference" "H2"
			(at -2.5146 -3.58013 0)
			(unlocked yes)
			(layer "F.SilkS")
			(effects
				(font
					(size 0.7874 0.5842)
					(thickness 0.1524)
				)
				(justify left)
			)
		)
		(property "Value" ""
			(at 0 0 0)
			(layer "F.Fab")
			(effects
				(font
					(size 1.27 1.27)
				)
			)
		)
		(duplicate_pad_numbers_are_jumpers no)
		(pad "1" thru_hole circle
			(at 0 0)
			(size 6.1976 6.1976)
			(drill 3.7338)
			(layers "*.Cu" "*.Mask")
			(remove_unused_layers no)
			(net "GND")
			(clearance -0.9779)
			(padstack
				(mode front_inner_back)
				(layer "Inner"
					(shape circle)
					(size 5.5372 5.5372)
					(clearance -0.6477)
				)
				(layer "B.Cu"
					(shape circle)
					(size 6.1976 6.1976)
					(clearance -0.9779)
				)
			)
		)
	)
	(footprint ""
		(layer "F.Cu")
		(at 112.649 -412.1658)
		(property "Reference" "C82"
			(at 0 0 0)
			(layer "F.SilkS")
			(hide yes)
			(effects
				(font
					(size 1.27 1.27)
				)
			)
		)
		(property "Value" ""
			(at 0 0 0)
			(layer "F.Fab")
			(effects
				(font
					(size 1.27 1.27)
				)
			)
		)
		(duplicate_pad_numbers_are_jumpers no)
		(fp_line
			(start -0.7874 -0.4064)
			(end 0.7874 -0.4064)
			(stroke
				(width 0.1524)
				(type default)
			)
			(layer "F.SilkS")
		)
		(fp_line
			(start -0.7874 0.4064)
			(end -0.7874 -0.4064)
			(stroke
				(width 0.1524)
				(type default)
			)
			(layer "F.SilkS")
		)
		(fp_line
			(start 0.7874 -0.4064)
			(end 0.7874 0.4064)
			(stroke
				(width 0.1524)
				(type default)
			)
			(layer "F.SilkS")
		)
		(fp_line
			(start 0.7874 0.4064)
			(end -0.7874 0.4064)
			(stroke
				(width 0.1524)
				(type default)
			)
			(layer "F.SilkS")
		)
		(fp_line
			(start -0.67945 -0.305054)
			(end -0.12065 -0.305054)
			(stroke
				(width 0.1)
				(type default)
			)
			(layer "F.Fab")
		)
		(fp_line
			(start -0.67945 0.3048)
			(end -0.67945 -0.305054)
			(stroke
				(width 0.1)
				(type default)
			)
			(layer "F.Fab")
		)
		(fp_line
			(start -0.12065 -0.305054)
			(end -0.12065 -0.2794)
			(stroke
				(width 0.1)
				(type default)
			)
			(layer "F.Fab")
		)
		(fp_line
			(start -0.12065 -0.2794)
			(end 0.12065 -0.2794)
			(stroke
				(width 0.1)
				(type default)
			)
			(layer "F.Fab")
		)
		(fp_line
			(start -0.12065 0.2794)
			(end -0.12065 0.3048)
			(stroke
				(width 0.1)
				(type default)
			)
			(layer "F.Fab")
		)
		(fp_line
			(start -0.12065 0.3048)
			(end -0.67945 0.3048)
			(stroke
				(width 0.1)
				(type default)
			)
			(layer "F.Fab")
		)
		(fp_line
			(start 0.120396 0.2794)
			(end -0.12065 0.2794)
			(stroke
				(width 0.1)
				(type default)
			)
			(layer "F.Fab")
		)
		(fp_line
			(start 0.120396 0.3048)
			(end 0.120396 0.2794)
			(stroke
				(width 0.1)
				(type default)
			)
			(layer "F.Fab")
		)
		(fp_line
			(start 0.12065 -0.3048)
			(end 0.67945 -0.3048)
			(stroke
				(width 0.1)
				(type default)
			)
			(layer "F.Fab")
		)
		(fp_line
			(start 0.12065 -0.2794)
			(end 0.12065 -0.3048)
			(stroke
				(width 0.1)
				(type default)
			)
			(layer "F.Fab")
		)
		(fp_line
			(start 0.67945 -0.3048)
			(end 0.67945 0.3048)
			(stroke
				(width 0.1)
				(type default)
			)
			(layer "F.Fab")
		)
		(fp_line
			(start 0.67945 0.3048)
			(end 0.120396 0.3048)
			(stroke
				(width 0.1)
				(type default)
			)
			(layer "F.Fab")
		)
		(pad "1" smd circle
			(at -0.40005 0)
			(size 0 0)
			(layers "F.Cu" "F.Mask" "F.Paste")
			(net "P3V3_9ZXL045_P1_VDDA")
		)
		(pad "2" smd circle
			(at 0.40005 0)
			(size 0 0)
			(layers "F.Cu" "F.Mask" "F.Paste")
			(net "GND")
		)
	)
	(footprint ""
		(layer "F.Cu")
		(at 436.608474 -103.768398 90)
		(property "Reference" "PR4525"
			(at 0 0 90)
			(layer "F.SilkS")
			(hide yes)
			(effects
				(font
					(size 1.27 1.27)
				)
			)
		)
		(property "Value" ""
			(at 0 0 90)
			(layer "F.Fab")
			(effects
				(font
					(size 1.27 1.27)
				)
			)
		)
		(duplicate_pad_numbers_are_jumpers no)
		(fp_line
			(start 0.7874 -0.4064)
			(end 0.7874 0.4064)
			(stroke
				(width 0.1524)
				(type default)
			)
			(layer "F.SilkS")
		)
		(fp_line
			(start -0.7874 -0.4064)
			(end 0.7874 -0.4064)
			(stroke
				(width 0.1524)
				(type default)
			)
			(layer "F.SilkS")
		)
		(fp_line
			(start 0.7874 0.4064)
			(end -0.7874 0.4064)
			(stroke
				(width 0.1524)
				(type default)
			)
			(layer "F.SilkS")
		)
		(fp_line
			(start -0.7874 0.4064)
			(end -0.7874 -0.4064)
			(stroke
				(width 0.1524)
				(type default)
			)
			(layer "F.SilkS")
		)
		(fp_line
			(start -0.12065 -0.305054)
			(end -0.12065 -0.2794)
			(stroke
				(width 0.1)
				(type default)
			)
			(layer "F.Fab")
		)
		(fp_line
			(start -0.67945 -0.305054)
			(end -0.12065 -0.305054)
			(stroke
				(width 0.1)
				(type default)
			)
			(layer "F.Fab")
		)
		(fp_line
			(start 0.67945 -0.3048)
			(end 0.67945 0.3048)
			(stroke
				(width 0.1)
				(type default)
			)
			(layer "F.Fab")
		)
		(fp_line
			(start 0.12065 -0.3048)
			(end 0.67945 -0.3048)
			(stroke
				(width 0.1)
				(type default)
			)
			(layer "F.Fab")
		)
		(fp_line
			(start 0.12065 -0.2794)
			(end 0.12065 -0.3048)
			(stroke
				(width 0.1)
				(type default)
			)
			(layer "F.Fab")
		)
		(fp_line
			(start -0.12065 -0.2794)
			(end 0.12065 -0.2794)
			(stroke
				(width 0.1)
				(type default)
			)
			(layer "F.Fab")
		)
		(fp_line
			(start 0.120396 0.2794)
			(end -0.12065 0.2794)
			(stroke
				(width 0.1)
				(type default)
			)
			(layer "F.Fab")
		)
		(fp_line
			(start -0.12065 0.2794)
			(end -0.12065 0.3048)
			(stroke
				(width 0.1)
				(type default)
			)
			(layer "F.Fab")
		)
		(fp_line
			(start 0.67945 0.3048)
			(end 0.120396 0.3048)
			(stroke
				(width 0.1)
				(type default)
			)
			(layer "F.Fab")
		)
		(fp_line
			(start 0.120396 0.3048)
			(end 0.120396 0.2794)
			(stroke
				(width 0.1)
				(type default)
			)
			(layer "F.Fab")
		)
		(fp_line
			(start -0.12065 0.3048)
			(end -0.67945 0.3048)
			(stroke
				(width 0.1)
				(type default)
			)
			(layer "F.Fab")
		)
		(fp_line
			(start -0.67945 0.3048)
			(end -0.67945 -0.305054)
			(stroke
				(width 0.1)
				(type default)
			)
			(layer "F.Fab")
		)
		(pad "1" smd circle
			(at -0.40005 0 90)
			(size 0 0)
			(layers "F.Cu" "F.Mask" "F.Paste")
			(net "P3V3_OCP_SFF_R")
		)
		(pad "2" smd circle
			(at 0.40005 0 90)
			(size 0 0)
			(layers "F.Cu" "F.Mask" "F.Paste")
			(net "P3V3_OCP_GATE_PU202_1")
		)
	)
	(footprint ""
		(layer "F.Cu")
		(at 339.699346 -23.897336 -90)
		(property "Reference" "R935"
			(at 0 0 270)
			(layer "F.SilkS")
			(hide yes)
			(effects
				(font
					(size 1.27 1.27)
				)
			)
		)
		(property "Value" ""
			(at 0 0 270)
			(layer "F.Fab")
			(effects
				(font
					(size 1.27 1.27)
				)
			)
		)
		(duplicate_pad_numbers_are_jumpers no)
		(fp_line
			(start -0.7874 0.4064)
			(end -0.7874 -0.4064)
			(stroke
				(width 0.1524)
				(type default)
			)
			(layer "F.SilkS")
		)
		(fp_line
			(start 0.7874 0.4064)
			(end -0.7874 0.4064)
			(stroke
				(width 0.1524)
				(type default)
			)
			(layer "F.SilkS")
		)
		(fp_line
			(start -0.7874 -0.4064)
			(end 0.7874 -0.4064)
			(stroke
				(width 0.1524)
				(type default)
			)
			(layer "F.SilkS")
		)
		(fp_line
			(start 0.7874 -0.4064)
			(end 0.7874 0.4064)
			(stroke
				(width 0.1524)
				(type default)
			)
			(layer "F.SilkS")
		)
		(fp_line
			(start -0.67945 0.3048)
			(end -0.67945 -0.305054)
			(stroke
				(width 0.1)
				(type default)
			)
			(layer "F.Fab")
		)
		(fp_line
			(start -0.12065 0.3048)
			(end -0.67945 0.3048)
			(stroke
				(width 0.1)
				(type default)
			)
			(layer "F.Fab")
		)
		(fp_line
			(start 0.120396 0.3048)
			(end 0.120396 0.2794)
			(stroke
				(width 0.1)
				(type default)
			)
			(layer "F.Fab")
		)
		(fp_line
			(start 0.67945 0.3048)
			(end 0.120396 0.3048)
			(stroke
				(width 0.1)
				(type default)
			)
			(layer "F.Fab")
		)
		(fp_line
			(start -0.12065 0.2794)
			(end -0.12065 0.3048)
			(stroke
				(width 0.1)
				(type default)
			)
			(layer "F.Fab")
		)
		(fp_line
			(start 0.120396 0.2794)
			(end -0.12065 0.2794)
			(stroke
				(width 0.1)
				(type default)
			)
			(layer "F.Fab")
		)
		(fp_line
			(start -0.12065 -0.2794)
			(end 0.12065 -0.2794)
			(stroke
				(width 0.1)
				(type default)
			)
			(layer "F.Fab")
		)
		(fp_line
			(start 0.12065 -0.2794)
			(end 0.12065 -0.3048)
			(stroke
				(width 0.1)
				(type default)
			)
			(layer "F.Fab")
		)
		(fp_line
			(start 0.12065 -0.3048)
			(end 0.67945 -0.3048)
			(stroke
				(width 0.1)
				(type default)
			)
			(layer "F.Fab")
		)
		(fp_line
			(start 0.67945 -0.3048)
			(end 0.67945 0.3048)
			(stroke
				(width 0.1)
				(type default)
			)
			(layer "F.Fab")
		)
		(fp_line
			(start -0.67945 -0.305054)
			(end -0.12065 -0.305054)
			(stroke
				(width 0.1)
				(type default)
			)
			(layer "F.Fab")
		)
		(fp_line
			(start -0.12065 -0.305054)
			(end -0.12065 -0.2794)
			(stroke
				(width 0.1)
				(type default)
			)
			(layer "F.Fab")
		)
		(pad "1" smd circle
			(at -0.40005 0 270)
			(size 0 0)
			(layers "F.Cu" "F.Mask" "F.Paste")
			(net "BOOT_RDY_BUF_R_LED")
		)
		(pad "2" smd circle
			(at 0.40005 0 270)
			(size 0 0)
			(layers "F.Cu" "F.Mask" "F.Paste")
			(net "BOOT_RDY_BUF_LED")
		)
	)
	(footprint ""
		(layer "F.Cu")
		(at 350.44761 -62.634876 180)
		(property "Reference" "R484"
			(at 0 0 180)
			(layer "F.SilkS")
			(hide yes)
			(effects
				(font
					(size 1.27 1.27)
				)
			)
		)
		(property "Value" ""
			(at 0 0 180)
			(layer "F.Fab")
			(effects
				(font
					(size 1.27 1.27)
				)
			)
		)
		(duplicate_pad_numbers_are_jumpers no)
		(fp_line
			(start 0.7874 0.4064)
			(end -0.7874 0.4064)
			(stroke
				(width 0.1524)
				(type default)
			)
			(layer "F.SilkS")
		)
		(fp_line
			(start 0.7874 -0.4064)
			(end 0.7874 0.4064)
			(stroke
				(width 0.1524)
				(type default)
			)
			(layer "F.SilkS")
		)
		(fp_line
			(start -0.7874 0.4064)
			(end -0.7874 -0.4064)
			(stroke
				(width 0.1524)
				(type default)
			)
			(layer "F.SilkS")
		)
		(fp_line
			(start -0.7874 -0.4064)
			(end 0.7874 -0.4064)
			(stroke
				(width 0.1524)
				(type default)
			)
			(layer "F.SilkS")
		)
		(fp_line
			(start 0.67945 0.3048)
			(end 0.120396 0.3048)
			(stroke
				(width 0.1)
				(type default)
			)
			(layer "F.Fab")
		)
		(fp_line
			(start 0.67945 -0.3048)
			(end 0.67945 0.3048)
			(stroke
				(width 0.1)
				(type default)
			)
			(layer "F.Fab")
		)
		(fp_line
			(start 0.12065 -0.2794)
			(end 0.12065 -0.3048)
			(stroke
				(width 0.1)
				(type default)
			)
			(layer "F.Fab")
		)
		(fp_line
			(start 0.12065 -0.3048)
			(end 0.67945 -0.3048)
			(stroke
				(width 0.1)
				(type default)
			)
			(layer "F.Fab")
		)
		(fp_line
			(start 0.120396 0.3048)
			(end 0.120396 0.2794)
			(stroke
				(width 0.1)
				(type default)
			)
			(layer "F.Fab")
		)
		(fp_line
			(start 0.120396 0.2794)
			(end -0.12065 0.2794)
			(stroke
				(width 0.1)
				(type default)
			)
			(layer "F.Fab")
		)
		(fp_line
			(start -0.12065 0.3048)
			(end -0.67945 0.3048)
			(stroke
				(width 0.1)
				(type default)
			)
			(layer "F.Fab")
		)
		(fp_line
			(start -0.12065 0.2794)
			(end -0.12065 0.3048)
			(stroke
				(width 0.1)
				(type default)
			)
			(layer "F.Fab")
		)
		(fp_line
			(start -0.12065 -0.2794)
			(end 0.12065 -0.2794)
			(stroke
				(width 0.1)
				(type default)
			)
			(layer "F.Fab")
		)
		(fp_line
			(start -0.12065 -0.305054)
			(end -0.12065 -0.2794)
			(stroke
				(width 0.1)
				(type default)
			)
			(layer "F.Fab")
		)
		(fp_line
			(start -0.67945 0.3048)
			(end -0.67945 -0.305054)
			(stroke
				(width 0.1)
				(type default)
			)
			(layer "F.Fab")
		)
		(fp_line
			(start -0.67945 -0.305054)
			(end -0.12065 -0.305054)
			(stroke
				(width 0.1)
				(type default)
			)
			(layer "F.Fab")
		)
		(pad "1" smd circle
			(at -0.40005 0 180)
			(size 0 0)
			(layers "F.Cu" "F.Mask" "F.Paste")
			(net "CPU0_XTRIG_L6")
		)
		(pad "2" smd circle
			(at 0.40005 0 180)
			(size 0 0)
			(layers "F.Cu" "F.Mask" "F.Paste")
			(net "CPU0_XTRIG_R1_L6")
		)
	)
	(footprint ""
		(layer "F.Cu")
		(at 181.688486 -426.349922 -90)
		(property "Reference" "R9018"
			(at 0 0 270)
			(layer "F.SilkS")
			(hide yes)
			(effects
				(font
					(size 1.27 1.27)
				)
			)
		)
		(property "Value" ""
			(at 0 0 270)
			(layer "F.Fab")
			(effects
				(font
					(size 1.27 1.27)
				)
			)
		)
		(duplicate_pad_numbers_are_jumpers no)
		(fp_line
			(start -0.7874 0.4064)
			(end -0.7874 -0.4064)
			(stroke
				(width 0.1524)
				(type default)
			)
			(layer "F.SilkS")
		)
		(fp_line
			(start 0.7874 0.4064)
			(end -0.7874 0.4064)
			(stroke
				(width 0.1524)
				(type default)
			)
			(layer "F.SilkS")
		)
		(fp_line
			(start -0.7874 -0.4064)
			(end 0.7874 -0.4064)
			(stroke
				(width 0.1524)
				(type default)
			)
			(layer "F.SilkS")
		)
		(fp_line
			(start 0.7874 -0.4064)
			(end 0.7874 0.4064)
			(stroke
				(width 0.1524)
				(type default)
			)
			(layer "F.SilkS")
		)
		(fp_line
			(start -0.67945 0.3048)
			(end -0.67945 -0.305054)
			(stroke
				(width 0.1)
				(type default)
			)
			(layer "F.Fab")
		)
		(fp_line
			(start -0.12065 0.3048)
			(end -0.67945 0.3048)
			(stroke
				(width 0.1)
				(type default)
			)
			(layer "F.Fab")
		)
		(fp_line
			(start 0.120396 0.3048)
			(end 0.120396 0.2794)
			(stroke
				(width 0.1)
				(type default)
			)
			(layer "F.Fab")
		)
		(fp_line
			(start 0.67945 0.3048)
			(end 0.120396 0.3048)
			(stroke
				(width 0.1)
				(type default)
			)
			(layer "F.Fab")
		)
		(fp_line
			(start -0.12065 0.2794)
			(end -0.12065 0.3048)
			(stroke
				(width 0.1)
				(type default)
			)
			(layer "F.Fab")
		)
		(fp_line
			(start 0.120396 0.2794)
			(end -0.12065 0.2794)
			(stroke
				(width 0.1)
				(type default)
			)
			(layer "F.Fab")
		)
		(fp_line
			(start -0.12065 -0.2794)
			(end 0.12065 -0.2794)
			(stroke
				(width 0.1)
				(type default)
			)
			(layer "F.Fab")
		)
		(fp_line
			(start 0.12065 -0.2794)
			(end 0.12065 -0.3048)
			(stroke
				(width 0.1)
				(type default)
			)
			(layer "F.Fab")
		)
		(fp_line
			(start 0.12065 -0.3048)
			(end 0.67945 -0.3048)
			(stroke
				(width 0.1)
				(type default)
			)
			(layer "F.Fab")
		)
		(fp_line
			(start 0.67945 -0.3048)
			(end 0.67945 0.3048)
			(stroke
				(width 0.1)
				(type default)
			)
			(layer "F.Fab")
		)
		(fp_line
			(start -0.67945 -0.305054)
			(end -0.12065 -0.305054)
			(stroke
				(width 0.1)
				(type default)
			)
			(layer "F.Fab")
		)
		(fp_line
			(start -0.12065 -0.305054)
			(end -0.12065 -0.2794)
			(stroke
				(width 0.1)
				(type default)
			)
			(layer "F.Fab")
		)
		(pad "1" smd circle
			(at -0.40005 0 270)
			(size 0 0)
			(layers "F.Cu" "F.Mask" "F.Paste")
			(net "PRSNT_CABLE_GPU_A3_ISO_N")
		)
		(pad "2" smd circle
			(at 0.40005 0 270)
			(size 0 0)
			(layers "F.Cu" "F.Mask" "F.Paste")
			(net "PRSNT_CABLE_GPU_A3_ISO_R_N")
		)
	)
	(footprint ""
		(layer "F.Cu")
		(at 82.706718 -19.142202 -90)
		(property "Reference" "R3825"
			(at 0 0 270)
			(layer "F.SilkS")
			(hide yes)
			(effects
				(font
					(size 1.27 1.27)
				)
			)
		)
		(property "Value" ""
			(at 0 0 270)
			(layer "F.Fab")
			(effects
				(font
					(size 1.27 1.27)
				)
			)
		)
		(duplicate_pad_numbers_are_jumpers no)
		(fp_line
			(start -0.7874 0.4064)
			(end -0.7874 -0.4064)
			(stroke
				(width 0.1524)
				(type default)
			)
			(layer "F.SilkS")
		)
		(fp_line
			(start 0.7874 0.4064)
			(end -0.7874 0.4064)
			(stroke
				(width 0.1524)
				(type default)
			)
			(layer "F.SilkS")
		)
		(fp_line
			(start -0.7874 -0.4064)
			(end 0.7874 -0.4064)
			(stroke
				(width 0.1524)
				(type default)
			)
			(layer "F.SilkS")
		)
		(fp_line
			(start 0.7874 -0.4064)
			(end 0.7874 0.4064)
			(stroke
				(width 0.1524)
				(type default)
			)
			(layer "F.SilkS")
		)
		(fp_line
			(start -0.67945 0.3048)
			(end -0.67945 -0.305054)
			(stroke
				(width 0.1)
				(type default)
			)
			(layer "F.Fab")
		)
		(fp_line
			(start -0.12065 0.3048)
			(end -0.67945 0.3048)
			(stroke
				(width 0.1)
				(type default)
			)
			(layer "F.Fab")
		)
		(fp_line
			(start 0.120396 0.3048)
			(end 0.120396 0.2794)
			(stroke
				(width 0.1)
				(type default)
			)
			(layer "F.Fab")
		)
		(fp_line
			(start 0.67945 0.3048)
			(end 0.120396 0.3048)
			(stroke
				(width 0.1)
				(type default)
			)
			(layer "F.Fab")
		)
		(fp_line
			(start -0.12065 0.2794)
			(end -0.12065 0.3048)
			(stroke
				(width 0.1)
				(type default)
			)
			(layer "F.Fab")
		)
		(fp_line
			(start 0.120396 0.2794)
			(end -0.12065 0.2794)
			(stroke
				(width 0.1)
				(type default)
			)
			(layer "F.Fab")
		)
		(fp_line
			(start -0.12065 -0.2794)
			(end 0.12065 -0.2794)
			(stroke
				(width 0.1)
				(type default)
			)
			(layer "F.Fab")
		)
		(fp_line
			(start 0.12065 -0.2794)
			(end 0.12065 -0.3048)
			(stroke
				(width 0.1)
				(type default)
			)
			(layer "F.Fab")
		)
		(fp_line
			(start 0.12065 -0.3048)
			(end 0.67945 -0.3048)
			(stroke
				(width 0.1)
				(type default)
			)
			(layer "F.Fab")
		)
		(fp_line
			(start 0.67945 -0.3048)
			(end 0.67945 0.3048)
			(stroke
				(width 0.1)
				(type default)
			)
			(layer "F.Fab")
		)
		(fp_line
			(start -0.67945 -0.305054)
			(end -0.12065 -0.305054)
			(stroke
				(width 0.1)
				(type default)
			)
			(layer "F.Fab")
		)
		(fp_line
			(start -0.12065 -0.305054)
			(end -0.12065 -0.2794)
			(stroke
				(width 0.1)
				(type default)
			)
			(layer "F.Fab")
		)
		(pad "1" smd circle
			(at -0.40005 0 270)
			(size 0 0)
			(layers "F.Cu" "F.Mask" "F.Paste")
			(net "P3V3_AUX")
		)
		(pad "2" smd circle
			(at 0.40005 0 270)
			(size 0 0)
			(layers "F.Cu" "F.Mask" "F.Paste")
			(net "HP_LVC3_OCP_V3_2_P12V_PWRGD")
		)
	)
)
